(kicad_pcb
	(version 20260206)
	(generator "pcbnew")
	(generator_version "10.0")
	(general
		(thickness 1.6)
		(legacy_teardrops no)
	)
	(paper "A4")
	(title_block
		(title "Bryce Canyon_F.DPB_16315-1-OCP.brd")
		(comment 1 "Bryce Canyon / footprints 2104-2108 of 2223")
	)
	(layers
		(0 "F.Cu" signal "TOP")
		(4 "In1.Cu" signal "L2GND")
		(6 "In2.Cu" signal "L3")
		(8 "In3.Cu" signal "L4GND")
		(10 "In4.Cu" signal "L5")
		(12 "In5.Cu" signal "L6VCC")
		(14 "In6.Cu" signal "L7VCC")
		(16 "In7.Cu" signal "L8")
		(18 "In8.Cu" signal "L9GND")
		(20 "In9.Cu" signal "L10")
		(22 "In10.Cu" signal "L11GND")
		(2 "B.Cu" signal "BOTTOM")
		(9 "F.Adhes" user "F.Adhesive")
		(11 "B.Adhes" user "B.Adhesive")
		(13 "F.Paste" user "Package Geometry/Pastemask Top")
		(15 "B.Paste" user "Package Geometry/Pastemask Bottom")
		(5 "F.SilkS" user "Ref Des/Silkscreen Top")
		(7 "B.SilkS" user "Ref Des/Silkscreen Bottom")
		(1 "F.Mask" user "Board Geometry/Soldermask Top")
		(3 "B.Mask" user "Board Geometry/Soldermask Bottom")
		(17 "Dwgs.User" user "User.Drawings")
		(19 "Cmts.User" user "User.Comments")
		(21 "Eco1.User" user "User.Eco1")
		(23 "Eco2.User" user "User.Eco2")
		(25 "Edge.Cuts" user "Board Geometry/Outline")
		(27 "Margin" user)
		(31 "F.CrtYd" user "Package Geometry/Place Bound Top")
		(29 "B.CrtYd" user "Package Geometry/Place Bound Bottom")
		(35 "F.Fab" user "Ref Des/Assembly Top")
		(33 "B.Fab" user "Ref Des/Assembly Bottom")
	)
	(footprint ""
		(layer "B.Cu")
		(at 23.6474 -247.0912 180)
		(property "Reference" "C600"
			(at 0 0 0)
			(layer "B.SilkS")
			(hide yes)
			(effects
				(font
					(size 1.27 1.27)
				)
				(justify mirror)
			)
		)
		(property "Value" "SCD1U16V2KX-3GP"
			(at -1.1811 -2.7051 180)
			(unlocked yes)
			(layer "B.Fab")
			(hide yes)
			(effects
				(font
					(size 1.016 1.016)
					(thickness 0.1524)
				)
				(justify mirror)
			)
		)
		(property "Device Type" "C402H22"
			(at -1.1811 -4.2291 180)
			(unlocked yes)
			(layer "B.Fab")
			(hide yes)
			(effects
				(font
					(size 1.016 1.016)
					(thickness 0.1524)
				)
				(justify mirror)
			)
		)
		(duplicate_pad_numbers_are_jumpers no)
		(fp_rect
			(start 0.4318 0.9525)
			(end -0.4318 -0.9525)
			(stroke
				(width 0)
				(type default)
			)
			(fill no)
			(layer "B.CrtYd")
		)
		(fp_rect
			(start 0.4318 0.9525)
			(end -0.4318 -0.9525)
			(stroke
				(width 0)
				(type default)
			)
			(fill no)
			(layer "B.Fab")
		)
		(pad "1" smd custom
			(at 0 -0.4445)
			(size 0.1524 0.1524)
			(layers "B.Cu" "B.Mask" "B.Paste")
			(net "P12V_A_VIN_U20")
			(options
				(clearance outline)
				(anchor circle)
			)
			(primitives
				(gr_poly
					(pts
						(arc
							(start 0.3048 0.2032)
							(mid 0.275042 0.275042)
							(end 0.2032 0.3048)
						)
						(arc
							(start -0.2032 0.3048)
							(mid -0.275042 0.275042)
							(end -0.3048 0.2032)
						)
						(arc
							(start -0.3048 -0.2032)
							(mid -0.275042 -0.275042)
							(end -0.2032 -0.3048)
						)
						(arc
							(start 0.2032 -0.3048)
							(mid 0.275042 -0.275042)
							(end 0.3048 -0.2032)
						)
					)
					(width 0)
					(fill yes)
				)
			)
		)
		(pad "2" smd custom
			(at 0 0.4445)
			(size 0.1524 0.1524)
			(layers "B.Cu" "B.Mask" "B.Paste")
			(net "GND")
			(options
				(clearance outline)
				(anchor circle)
			)
			(primitives
				(gr_poly
					(pts
						(arc
							(start 0.3048 0.2032)
							(mid 0.275042 0.275042)
							(end 0.2032 0.3048)
						)
						(arc
							(start -0.2032 0.3048)
							(mid -0.275042 0.275042)
							(end -0.3048 0.2032)
						)
						(arc
							(start -0.3048 -0.2032)
							(mid -0.275042 -0.275042)
							(end -0.2032 -0.3048)
						)
						(arc
							(start 0.2032 -0.3048)
							(mid 0.275042 -0.275042)
							(end 0.3048 -0.2032)
						)
					)
					(width 0)
					(fill yes)
				)
			)
		)
	)
	(footprint ""
		(layer "B.Cu")
		(at 440.362594 -254.514096 90)
		(property "Reference" "C641"
			(at 0 0 90)
			(layer "B.SilkS")
			(hide yes)
			(effects
				(font
					(size 1.27 1.27)
				)
				(justify mirror)
			)
		)
		(property "Value" "SC1U16V3KX-5GP"
			(at 0 -2.8194 90)
			(unlocked yes)
			(layer "B.Fab")
			(hide yes)
			(effects
				(font
					(size 1.016 1.016)
					(thickness 0.1524)
				)
				(justify mirror)
			)
		)
		(property "Device Type" "C603H36"
			(at 0 -4.3434 90)
			(unlocked yes)
			(layer "B.Fab")
			(hide yes)
			(effects
				(font
					(size 1.016 1.016)
					(thickness 0.1524)
				)
				(justify mirror)
			)
		)
		(duplicate_pad_numbers_are_jumpers no)
		(fp_line
			(start -0.508 0)
			(end 0.508 0)
			(stroke
				(width 0.2032)
				(type default)
			)
			(layer "B.SilkS")
		)
		(fp_rect
			(start 0.5842 1.3335)
			(end -0.5842 -1.3335)
			(stroke
				(width 0)
				(type default)
			)
			(fill no)
			(layer "B.CrtYd")
		)
		(fp_rect
			(start 0.5842 1.3335)
			(end -0.5842 -1.3335)
			(stroke
				(width 0)
				(type default)
			)
			(fill no)
			(layer "B.Fab")
		)
		(pad "1" smd custom
			(at 0 -0.762 270)
			(size 0.2159 0.2159)
			(layers "B.Cu" "B.Mask" "B.Paste")
			(net "GND")
			(options
				(clearance outline)
				(anchor circle)
			)
			(primitives
				(gr_poly
					(pts
						(arc
							(start -0.3302 0.4318)
							(mid -0.402042 0.402042)
							(end -0.4318 0.3302)
						)
						(arc
							(start -0.4318 -0.3302)
							(mid -0.402042 -0.402042)
							(end -0.3302 -0.4318)
						)
						(arc
							(start 0.3302 -0.4318)
							(mid 0.402042 -0.402042)
							(end 0.4318 -0.3302)
						)
						(arc
							(start 0.4318 0.3302)
							(mid 0.402042 0.402042)
							(end 0.3302 0.4318)
						)
					)
					(width 0)
					(fill yes)
				)
			)
		)
		(pad "2" smd custom
			(at 0 0.762 270)
			(size 0.2159 0.2159)
			(layers "B.Cu" "B.Mask" "B.Paste")
			(net "P5V_C_VREG")
			(options
				(clearance outline)
				(anchor circle)
			)
			(primitives
				(gr_poly
					(pts
						(arc
							(start -0.3302 0.4318)
							(mid -0.402042 0.402042)
							(end -0.4318 0.3302)
						)
						(arc
							(start -0.4318 -0.3302)
							(mid -0.402042 -0.402042)
							(end -0.3302 -0.4318)
						)
						(arc
							(start 0.3302 -0.4318)
							(mid 0.402042 -0.402042)
							(end 0.4318 -0.3302)
						)
						(arc
							(start 0.4318 0.3302)
							(mid 0.402042 0.402042)
							(end 0.3302 0.4318)
						)
					)
					(width 0)
					(fill yes)
				)
			)
		)
	)
	(footprint ""
		(layer "B.Cu")
		(at 29.4132 -248.7168 -90)
		(property "Reference" "U20"
			(at 0 0 90)
			(layer "B.SilkS")
			(hide yes)
			(effects
				(font
					(size 1.27 1.27)
				)
				(justify mirror)
			)
		)
		(property "Value" "TPS53319DQPR-GP"
			(at -4.7498 -5.6896 270)
			(unlocked yes)
			(layer "B.Fab")
			(hide yes)
			(effects
				(font
					(size 1.016 1.016)
					(thickness 0.1524)
				)
				(justify mirror)
			)
		)
		(property "Device Type" "QFN22G6050-G6133H60"
			(at -4.7498 -7.2136 270)
			(unlocked yes)
			(layer "B.Fab")
			(hide yes)
			(effects
				(font
					(size 1.016 1.016)
					(thickness 0.1524)
				)
				(justify mirror)
			)
		)
		(duplicate_pad_numbers_are_jumpers no)
		(fp_line
			(start -3.556 3.5179)
			(end -3.556 2.2479)
			(stroke
				(width 0.1524)
				(type default)
			)
			(layer "B.SilkS")
		)
		(fp_line
			(start -2.286 3.5179)
			(end -3.556 3.5179)
			(stroke
				(width 0.1524)
				(type default)
			)
			(layer "B.SilkS")
		)
		(fp_line
			(start 3.556 3.5179)
			(end 2.286 3.5179)
			(stroke
				(width 0.1524)
				(type default)
			)
			(layer "B.SilkS")
		)
		(fp_line
			(start -1.500124 3.262122)
			(end -1.500124 4.024122)
			(stroke
				(width 0.1524)
				(type default)
			)
			(layer "B.SilkS")
		)
		(fp_line
			(start 0.999998 3.262122)
			(end 0.999998 3.770122)
			(stroke
				(width 0.1524)
				(type default)
			)
			(layer "B.SilkS")
		)
		(fp_line
			(start 3.556 2.2479)
			(end 3.556 3.5179)
			(stroke
				(width 0.1524)
				(type default)
			)
			(layer "B.SilkS")
		)
		(fp_line
			(start -0.500126 -3.262122)
			(end -0.500126 -3.770122)
			(stroke
				(width 0.1524)
				(type default)
			)
			(layer "B.SilkS")
		)
		(fp_line
			(start 1.999996 -3.262122)
			(end 1.999996 -4.024122)
			(stroke
				(width 0.1524)
				(type default)
			)
			(layer "B.SilkS")
		)
		(fp_line
			(start 2.286 -3.5179)
			(end 3.556 -3.5179)
			(stroke
				(width 0.1524)
				(type default)
			)
			(layer "B.SilkS")
		)
		(fp_line
			(start 3.556 -3.5179)
			(end 3.556 -2.2479)
			(stroke
				(width 0.1524)
				(type default)
			)
			(layer "B.SilkS")
		)
		(fp_poly
			(pts
				(xy -3.556 -3.5179) (xy -2.5273 -3.5179) (xy -3.556 -2.4892)
			)
			(stroke
				(width 0)
				(type default)
			)
			(fill yes)
			(layer "B.SilkS")
		)
		(fp_rect
			(start 2.9972 2.5019)
			(end -2.9972 -2.5019)
			(stroke
				(width 0)
				(type default)
			)
			(fill no)
			(layer "B.CrtYd")
		)
		(fp_poly
			(pts
				(xy -3.556 -2.5019) (xy 2.9972 -2.5019) (xy 2.9972 2.5019) (xy -2.9972 2.5019) (xy -2.9972 -2.4892)
				(xy -3.556 -2.4892) (xy -3.556 3.5179) (xy 3.556 3.5179) (xy 3.556 -3.5179) (xy -3.556 -3.5179)
			)
			(stroke
				(width 0)
				(type default)
			)
			(fill no)
			(layer "B.CrtYd")
		)
		(fp_rect
			(start 3.556 3.5179)
			(end -3.556 -3.5179)
			(stroke
				(width 0)
				(type default)
			)
			(fill no)
			(layer "B.Fab")
		)
		(pad "1" smd rect
			(at -2.500122 -2.449322 90)
			(size 0.3048 1.1176)
			(layers "B.Cu" "B.Mask" "B.Paste")
			(net "P5V_A_VFB")
		)
		(pad "2" smd rect
			(at -1.999996 -2.449322 90)
			(size 0.3048 1.1176)
			(layers "B.Cu" "B.Mask" "B.Paste")
			(net "P5V_A_EN_R")
		)
		(pad "3" smd rect
			(at -1.500124 -2.449322 90)
			(size 0.3048 1.1176)
			(layers "B.Cu" "B.Mask" "B.Paste")
			(net "P5V_A_1_PGOOD")
		)
		(pad "4" smd rect
			(at -0.999998 -2.449322 90)
			(size 0.3048 1.1176)
			(layers "B.Cu" "B.Mask" "B.Paste")
			(net "P5V_A_VBST")
		)
		(pad "5" smd rect
			(at -0.500126 -2.449322 90)
			(size 0.3048 1.1176)
			(layers "B.Cu" "B.Mask" "B.Paste")
			(net "P5V_A_ROVP")
		)
		(pad "6" smd rect
			(at 0 -2.449322 90)
			(size 0.3048 1.1176)
			(layers "B.Cu" "B.Mask" "B.Paste")
			(net "P5V_A_LL")
		)
		(pad "7" smd rect
			(at 0.500126 -2.449322 90)
			(size 0.3048 1.1176)
			(layers "B.Cu" "B.Mask" "B.Paste")
			(net "P5V_A_LL")
		)
		(pad "8" smd rect
			(at 0.999998 -2.449322 90)
			(size 0.3048 1.1176)
			(layers "B.Cu" "B.Mask" "B.Paste")
			(net "P5V_A_LL")
		)
		(pad "9" smd rect
			(at 1.500124 -2.449322 90)
			(size 0.3048 1.1176)
			(layers "B.Cu" "B.Mask" "B.Paste")
			(net "P5V_A_LL")
		)
		(pad "10" smd rect
			(at 1.999996 -2.449322 90)
			(size 0.3048 1.1176)
			(layers "B.Cu" "B.Mask" "B.Paste")
			(net "P5V_A_LL")
		)
		(pad "11" smd rect
			(at 2.500122 -2.449322 90)
			(size 0.3048 1.1176)
			(layers "B.Cu" "B.Mask" "B.Paste")
			(net "P5V_A_LL")
		)
		(pad "12" smd rect
			(at 2.500122 2.449322 90)
			(size 0.3048 1.1176)
			(layers "B.Cu" "B.Mask" "B.Paste")
			(net "P12V_A_VIN_U20")
		)
		(pad "13" smd rect
			(at 1.999996 2.449322 90)
			(size 0.3048 1.1176)
			(layers "B.Cu" "B.Mask" "B.Paste")
			(net "P12V_A_VIN_U20")
		)
		(pad "14" smd rect
			(at 1.500124 2.449322 90)
			(size 0.3048 1.1176)
			(layers "B.Cu" "B.Mask" "B.Paste")
			(net "P12V_A_VIN_U20")
		)
		(pad "15" smd rect
			(at 0.999998 2.449322 90)
			(size 0.3048 1.1176)
			(layers "B.Cu" "B.Mask" "B.Paste")
			(net "P12V_A_VIN_U20")
		)
		(pad "16" smd rect
			(at 0.500126 2.449322 90)
			(size 0.3048 1.1176)
			(layers "B.Cu" "B.Mask" "B.Paste")
			(net "P12V_A_VIN_U20")
		)
		(pad "17" smd rect
			(at 0 2.449322 90)
			(size 0.3048 1.1176)
			(layers "B.Cu" "B.Mask" "B.Paste")
			(net "P12V_A_VIN_U20")
		)
		(pad "18" smd rect
			(at -0.500126 2.449322 90)
			(size 0.3048 1.1176)
			(layers "B.Cu" "B.Mask" "B.Paste")
			(net "P5V_A_VREG")
		)
		(pad "19" smd rect
			(at -0.999998 2.449322 90)
			(size 0.3048 1.1176)
			(layers "B.Cu" "B.Mask" "B.Paste")
			(net "P12V_A_VDD_U20")
		)
		(pad "20" smd rect
			(at -1.500124 2.449322 90)
			(size 0.3048 1.1176)
			(layers "B.Cu" "B.Mask" "B.Paste")
			(net "P5V_A_MODE")
		)
		(pad "21" smd rect
			(at -1.999996 2.449322 90)
			(size 0.3048 1.1176)
			(layers "B.Cu" "B.Mask" "B.Paste")
			(net "P5V_A_TRIP")
		)
		(pad "22" smd rect
			(at -2.500122 2.449322 90)
			(size 0.3048 1.1176)
			(layers "B.Cu" "B.Mask" "B.Paste")
			(net "P5V_A_RF")
		)
		(pad "23" smd custom
			(at 0 0 90)
			(size 0.83185 0.83185)
			(layers "B.Cu" "B.Mask" "B.Paste")
			(net "GND")
			(options
				(clearance outline)
				(anchor circle)
			)
			(primitives
				(gr_poly
					(pts
						(xy -2.7813 -1.6637) (xy -2.7813 -1.2954) (xy -3.048 -1.2954) (xy -3.048 -0.9525) (xy -2.7813 -0.9525)
						(xy -2.7813 0.9525) (xy -3.048 0.9525) (xy -3.048 1.2954) (xy -2.7813 1.2954) (xy -2.7813 1.6637)
						(xy 2.7813 1.6637) (xy 2.7813 1.2954) (xy 3.048 1.2954) (xy 3.048 0.9525) (xy 2.7813 0.9525) (xy 2.7813 -0.9525)
						(xy 3.048 -0.9525) (xy 3.048 -1.2954) (xy 2.7813 -1.2954) (xy 2.7813 -1.6637)
					)
					(width 0)
					(fill yes)
				)
			)
		)
	)
	(footprint ""
		(layer "B.Cu")
		(at 180.774594 -224.3328)
		(property "Reference" "R1292"
			(at 0 0 0)
			(layer "B.SilkS")
			(hide yes)
			(effects
				(font
					(size 1.27 1.27)
				)
				(justify mirror)
			)
		)
		(property "Value" "0R2J-2-GP"
			(at -0.064008 -3.993896 0)
			(unlocked yes)
			(layer "B.Fab")
			(hide yes)
			(effects
				(font
					(size 1.016 1.016)
					(thickness 0.1524)
				)
				(justify mirror)
			)
		)
		(property "Device Type" "R402H16"
			(at -0.064008 -5.517896 0)
			(unlocked yes)
			(layer "B.Fab")
			(hide yes)
			(effects
				(font
					(size 1.016 1.016)
					(thickness 0.1524)
				)
				(justify mirror)
			)
		)
		(duplicate_pad_numbers_are_jumpers no)
		(fp_line
			(start -0.508 -0.9398)
			(end 0.508 -0.9398)
			(stroke
				(width 0.1524)
				(type default)
			)
			(layer "B.SilkS")
		)
		(fp_line
			(start 0.508 -0.9398)
			(end 0.508 0.9398)
			(stroke
				(width 0.1524)
				(type default)
			)
			(layer "B.SilkS")
		)
		(fp_rect
			(start 0.508 0.9398)
			(end -0.508 -0.9398)
			(stroke
				(width 0)
				(type default)
			)
			(fill no)
			(layer "B.CrtYd")
		)
		(fp_rect
			(start 0.508 0.9398)
			(end -0.508 -0.9398)
			(stroke
				(width 0)
				(type default)
			)
			(fill no)
			(layer "B.Fab")
		)
		(pad "1" smd custom
			(at 0 -0.4445 180)
			(size 0.1397 0.1397)
			(layers "B.Cu" "B.Mask" "B.Paste")
			(net "P3V3_STBY_EN_R")
			(options
				(clearance outline)
				(anchor circle)
			)
			(primitives
				(gr_poly
					(pts
						(arc
							(start -0.1778 0.2794)
							(mid -0.249642 0.249642)
							(end -0.2794 0.1778)
						)
						(arc
							(start -0.2794 -0.1778)
							(mid -0.249642 -0.249642)
							(end -0.1778 -0.2794)
						)
						(arc
							(start 0.1778 -0.2794)
							(mid 0.249642 -0.249642)
							(end 0.2794 -0.1778)
						)
						(arc
							(start 0.2794 0.1778)
							(mid 0.249642 0.249642)
							(end 0.1778 0.2794)
						)
					)
					(width 0)
					(fill yes)
				)
			)
		)
		(pad "2" smd custom
			(at 0 0.4445 180)
			(size 0.1397 0.1397)
			(layers "B.Cu" "B.Mask" "B.Paste")
			(net "P12V_A_PGOOD")
			(options
				(clearance outline)
				(anchor circle)
			)
			(primitives
				(gr_poly
					(pts
						(arc
							(start -0.1778 0.2794)
							(mid -0.249642 0.249642)
							(end -0.2794 0.1778)
						)
						(arc
							(start -0.2794 -0.1778)
							(mid -0.249642 -0.249642)
							(end -0.1778 -0.2794)
						)
						(arc
							(start 0.1778 -0.2794)
							(mid 0.249642 -0.249642)
							(end 0.2794 -0.1778)
						)
						(arc
							(start 0.2794 0.1778)
							(mid 0.249642 0.249642)
							(end 0.1778 0.2794)
						)
					)
					(width 0)
					(fill yes)
				)
			)
		)
	)
	(footprint ""
		(layer "B.Cu")
		(at 49.2252 -148.7678 90)
		(property "Reference" "R1236"
			(at 0 0 90)
			(layer "B.SilkS")
			(hide yes)
			(effects
				(font
					(size 1.27 1.27)
				)
				(justify mirror)
			)
		)
		(property "Value" "71K5R2F-GP"
			(at -0.064008 -3.993896 90)
			(unlocked yes)
			(layer "B.Fab")
			(hide yes)
			(effects
				(font
					(size 1.016 1.016)
					(thickness 0.1524)
				)
				(justify mirror)
			)
		)
		(property "Device Type" "R402H16"
			(at -0.064008 -5.517896 90)
			(unlocked yes)
			(layer "B.Fab")
			(hide yes)
			(effects
				(font
					(size 1.016 1.016)
					(thickness 0.1524)
				)
				(justify mirror)
			)
		)
		(duplicate_pad_numbers_are_jumpers no)
		(fp_line
			(start 0.508 -0.9398)
			(end 0.508 0.9398)
			(stroke
				(width 0.1524)
				(type default)
			)
			(layer "B.SilkS")
		)
		(fp_line
			(start -0.508 -0.9398)
			(end 0.508 -0.9398)
			(stroke
				(width 0.1524)
				(type default)
			)
			(layer "B.SilkS")
		)
		(fp_rect
			(start 0.508 0.9398)
			(end -0.508 -0.9398)
			(stroke
				(width 0)
				(type default)
			)
			(fill no)
			(layer "B.CrtYd")
		)
		(fp_rect
			(start 0.508 0.9398)
			(end -0.508 -0.9398)
			(stroke
				(width 0)
				(type default)
			)
			(fill no)
			(layer "B.Fab")
		)
		(pad "1" smd custom
			(at 0 -0.4445 270)
			(size 0.1397 0.1397)
			(layers "B.Cu" "B.Mask" "B.Paste")
			(net "P5V_B_VFB")
			(options
				(clearance outline)
				(anchor circle)
			)
			(primitives
				(gr_poly
					(pts
						(arc
							(start -0.1778 0.2794)
							(mid -0.249642 0.249642)
							(end -0.2794 0.1778)
						)
						(arc
							(start -0.2794 -0.1778)
							(mid -0.249642 -0.249642)
							(end -0.1778 -0.2794)
						)
						(arc
							(start 0.1778 -0.2794)
							(mid 0.249642 -0.249642)
							(end 0.2794 -0.1778)
						)
						(arc
							(start 0.2794 0.1778)
							(mid 0.249642 0.249642)
							(end 0.1778 0.2794)
						)
					)
					(width 0)
					(fill yes)
				)
			)
		)
		(pad "2" smd custom
			(at 0 0.4445 270)
			(size 0.1397 0.1397)
			(layers "B.Cu" "B.Mask" "B.Paste")
			(net "P5V_B_VFB_R")
			(options
				(clearance outline)
				(anchor circle)
			)
			(primitives
				(gr_poly
					(pts
						(arc
							(start -0.1778 0.2794)
							(mid -0.249642 0.249642)
							(end -0.2794 0.1778)
						)
						(arc
							(start -0.2794 -0.1778)
							(mid -0.249642 -0.249642)
							(end -0.1778 -0.2794)
						)
						(arc
							(start 0.1778 -0.2794)
							(mid 0.249642 -0.249642)
							(end 0.2794 -0.1778)
						)
						(arc
							(start 0.2794 0.1778)
							(mid 0.249642 0.249642)
							(end 0.1778 0.2794)
						)
					)
					(width 0)
					(fill yes)
				)
			)
		)
	)
)
